# TIMECARD (Time Appliance Project (Time Card)) — schematic netlist excerpt (pin names and nets, part order shuffled) for the footprints in the layout excerpt that follows; sources: Cadence DE-HDL packaged netlist, KiCad conversion of R4006-B0001-02_R01.brd

C107  CAPACITOR  0.1UF 10V 10%  pkg SMC_0402R_H022  page 14 : \1\ = XP3R3V_FPGA ; \2\ = SG
R447  RESISTOR  10KOHM 1%  pkg SMC_0402R_H016  page 24 : \1\ = XP3R3V_FT4232 ; \2\ = FTDI_EE_CLK

(kicad_pcb
	(version 20260206)
	(generator "pcbnew")
	(generator_version "10.0")
	(general
		(thickness 1.6)
		(legacy_teardrops no)
	)
	(paper "A4")
	(title_block
		(title "timecard-production-celestica-r4006 — R4006-B0001-02_R01.brd")
		(comment 1 "Time Appliance Project (Time Card) / footprints 1104-1105 of 1113")
	)
	(layers
		(0 "F.Cu" signal "TOP")
		(4 "In1.Cu" signal "L02_GND1")
		(6 "In2.Cu" signal "L03_SIG1")
		(8 "In3.Cu" signal "L04_GND2")
		(10 "In4.Cu" signal "L05_VCC1")
		(12 "In5.Cu" signal "L06_VCC2")
		(14 "In6.Cu" signal "L07_GND3")
		(16 "In7.Cu" signal "L08_SIG2")
		(18 "In8.Cu" signal "L09_GND4")
		(2 "B.Cu" signal "BOTTOM")
		(9 "F.Adhes" user "F.Adhesive")
		(11 "B.Adhes" user "B.Adhesive")
		(13 "F.Paste" user "Package Geometry/Pastemask Top")
		(15 "B.Paste" user "Package Geometry/Pastemask Bottom")
		(5 "F.SilkS" user "Ref Des/Silkscreen Top")
		(7 "B.SilkS" user "Ref Des/Silkscreen Bottom")
		(1 "F.Mask" user "Board Geometry/Soldermask Top")
		(3 "B.Mask" user "Board Geometry/Soldermask Bottom")
		(17 "Dwgs.User" user "User.Drawings")
		(19 "Cmts.User" user "User.Comments")
		(21 "Eco1.User" user "User.Eco1")
		(23 "Eco2.User" user "User.Eco2")
		(25 "Edge.Cuts" user "Board Geometry/Outline")
		(27 "Margin" user)
		(31 "F.CrtYd" user "Package Geometry/Place Bound Top")
		(29 "B.CrtYd" user "Package Geometry/Place Bound Bottom")
		(35 "F.Fab" user "Ref Des/Assembly Top")
		(33 "B.Fab" user "Ref Des/Assembly Bottom")
	)
	(footprint ""
		(layer "B.Cu")
		(at 53.975 -88.9)
		(property "Reference" "R447"
			(at 0.127 -4.40563 0)
			(unlocked yes)
			(layer "B.SilkS")
			(effects
				(font
					(size 0.7874 0.5842)
					(thickness 0.1524)
				)
				(justify mirror)
			)
		)
		(property "Value" "VAL*"
			(at -0.02032 2.13233 0)
			(unlocked yes)
			(layer "B.Fab")
			(hide yes)
			(effects
				(font
					(size 0.7874 0.5842)
					(thickness 0.1524)
				)
				(justify mirror)
			)
		)
		(property "Tolerance" "TOL*"
			(at -0.044704 3.05435 0)
			(unlocked yes)
			(layer "Cmts.User")
			(hide yes)
			(effects
				(font
					(size 0.7874 0.5842)
					(thickness 0.1524)
				)
				(justify mirror)
			)
		)
		(property "User Part Number" "PARTNUM*"
			(at -0.02032 4.024884 0)
			(unlocked yes)
			(layer "Cmts.User")
			(hide yes)
			(effects
				(font
					(size 0.7874 0.5842)
					(thickness 0.1524)
				)
				(justify mirror)
			)
		)
		(property "Device Type" "RESISTOR-G155-11002-01,10KOHM,A"
			(at -0.008382 1.210564 0)
			(unlocked yes)
			(layer "B.Fab")
			(hide yes)
			(effects
				(font
					(size 0.7874 0.5842)
					(thickness 0.1524)
				)
				(justify mirror)
			)
		)
		(duplicate_pad_numbers_are_jumpers no)
		(fp_line
			(start -1.143 -0.5588)
			(end 1.143 -0.5588)
			(stroke
				(width 0.1)
				(type default)
			)
			(layer "B.SilkS")
		)
		(fp_line
			(start -1.143 0.5588)
			(end -1.143 -0.5588)
			(stroke
				(width 0.1)
				(type default)
			)
			(layer "B.SilkS")
		)
		(fp_line
			(start 1.143 -0.5588)
			(end 1.143 0.5588)
			(stroke
				(width 0.1)
				(type default)
			)
			(layer "B.SilkS")
		)
		(fp_line
			(start 1.143 0.5588)
			(end -1.143 0.5588)
			(stroke
				(width 0.1)
				(type default)
			)
			(layer "B.SilkS")
		)
		(fp_poly
			(pts
				(xy 1.143 0.5588) (xy -1.143 0.5588) (xy -1.143 -0.5588) (xy 1.143 -0.5588)
			)
			(stroke
				(width 0)
				(type default)
			)
			(fill no)
			(layer "B.CrtYd")
		)
		(fp_line
			(start -0.508 -0.3048)
			(end 0.508 -0.3048)
			(stroke
				(width 0.1)
				(type default)
			)
			(layer "B.Fab")
		)
		(fp_line
			(start -0.508 0.3048)
			(end -0.508 -0.3048)
			(stroke
				(width 0.1)
				(type default)
			)
			(layer "B.Fab")
		)
		(fp_line
			(start 0.508 -0.3048)
			(end 0.508 0.3048)
			(stroke
				(width 0.1)
				(type default)
			)
			(layer "B.Fab")
		)
		(fp_line
			(start 0.508 0.3048)
			(end -0.508 0.3048)
			(stroke
				(width 0.1)
				(type default)
			)
			(layer "B.Fab")
		)
		(pad "1" smd rect
			(at 0.5334 0 180)
			(size 0.7112 0.6096)
			(layers "B.Cu" "B.Mask" "B.Paste")
			(net "XP3R3V_FT4232")
		)
		(pad "2" smd rect
			(at -0.5334 0 180)
			(size 0.7112 0.6096)
			(layers "B.Cu" "B.Mask" "B.Paste")
			(net "FTDI_EE_CLK")
		)
		(zone
			(layer "B.Cu")
			(hatch none 0.5)
			(connect_pads
				(clearance 0)
			)
			(min_thickness 0.25)
			(keepout
				(tracks allowed)
				(vias not_allowed)
				(pads allowed)
				(copperpour not_allowed)
				(footprints allowed)
			)
			(placement
				(enabled no)
				(sheetname "")
			)
			(fill
				(thermal_gap 0.5)
				(thermal_bridge_width 0.5)
				(island_removal_mode 0)
			)
			(polygon
				(pts
					(xy 54.0512 -88.5952) (xy 54.0512 -89.2048) (xy 53.8988 -89.2048) (xy 53.8988 -88.5952)
				)
			)
		)
		(zone
			(layer "B.Cu")
			(hatch none 0.5)
			(connect_pads
				(clearance 0)
			)
			(min_thickness 0.25)
			(keepout
				(tracks not_allowed)
				(vias allowed)
				(pads allowed)
				(copperpour not_allowed)
				(footprints allowed)
			)
			(placement
				(enabled no)
				(sheetname "")
			)
			(fill
				(thermal_gap 0.5)
				(thermal_bridge_width 0.5)
				(island_removal_mode 0)
			)
			(polygon
				(pts
					(xy 54.0512 -88.5952) (xy 54.0512 -89.2048) (xy 53.8988 -89.2048) (xy 53.8988 -88.5952)
				)
			)
		)
	)
	(footprint ""
		(layer "B.Cu")
		(at 114.847116 -46.32325 -90)
		(property "Reference" "C107"
			(at 2.00025 43.123866 270)
			(unlocked yes)
			(layer "B.SilkS")
			(effects
				(font
					(size 0.635 0.4064)
					(thickness 0.1524)
				)
				(justify mirror)
			)
		)
		(property "Value" "VAL*"
			(at 0 3.718306 270)
			(unlocked yes)
			(layer "B.Fab")
			(hide yes)
			(effects
				(font
					(size 0.7874 0.5842)
					(thickness 0.127)
				)
				(justify mirror)
			)
		)
		(property "Device Type" "CAPACITOR-G105-0B104-CK,0.1UF,A"
			(at 0 1.432306 270)
			(unlocked yes)
			(layer "B.Fab")
			(hide yes)
			(effects
				(font
					(size 0.7874 0.5842)
					(thickness 0.127)
				)
				(justify mirror)
			)
		)
		(property "User Part Number" "PARTNUM*"
			(at 0 2.575306 270)
			(unlocked yes)
			(layer "Cmts.User")
			(hide yes)
			(effects
				(font
					(size 0.7874 0.5842)
					(thickness 0.127)
				)
				(justify mirror)
			)
		)
		(property "Tolerance" "TOL*"
			(at 0 4.861306 270)
			(unlocked yes)
			(layer "Cmts.User")
			(hide yes)
			(effects
				(font
					(size 0.7874 0.5842)
					(thickness 0.127)
				)
				(justify mirror)
			)
		)
		(duplicate_pad_numbers_are_jumpers no)
		(fp_line
			(start -0.970026 0.4699)
			(end 0.970026 0.4699)
			(stroke
				(width 0.1)
				(type default)
			)
			(layer "B.SilkS")
		)
		(fp_line
			(start 0.970026 0.4699)
			(end 0.970026 -0.4699)
			(stroke
				(width 0.1)
				(type default)
			)
			(layer "B.SilkS")
		)
		(fp_line
			(start -0.970026 -0.4699)
			(end -0.970026 0.4699)
			(stroke
				(width 0.1)
				(type default)
			)
			(layer "B.SilkS")
		)
		(fp_line
			(start 0.970026 -0.4699)
			(end -0.970026 -0.4699)
			(stroke
				(width 0.1)
				(type default)
			)
			(layer "B.SilkS")
		)
		(fp_poly
			(pts
				(xy 0.970026 0.4699) (xy -0.970026 0.4699) (xy -0.970026 -0.4699) (xy 0.970026 -0.4699)
			)
			(stroke
				(width 0)
				(type default)
			)
			(fill no)
			(layer "B.CrtYd")
		)
		(fp_line
			(start -0.508 0.3048)
			(end 0.508 0.3048)
			(stroke
				(width 0.1)
				(type default)
			)
			(layer "B.Fab")
		)
		(fp_line
			(start 0.508 0.3048)
			(end 0.508 -0.3048)
			(stroke
				(width 0.1)
				(type default)
			)
			(layer "B.Fab")
		)
		(fp_line
			(start -0.508 -0.3048)
			(end -0.508 0.3048)
			(stroke
				(width 0.1)
				(type default)
			)
			(layer "B.Fab")
		)
		(fp_line
			(start 0.508 -0.3048)
			(end -0.508 -0.3048)
			(stroke
				(width 0.1)
				(type default)
			)
			(layer "B.Fab")
		)
		(pad "1" smd circle
			(at 0.500126 0 90)
			(size 0.635 0.635)
			(layers "B.Cu" "B.Mask" "B.Paste")
			(net "XP3R3V_FPGA")
		)
		(pad "2" smd circle
			(at -0.500126 0 90)
			(size 0.635 0.635)
			(layers "B.Cu" "B.Mask" "B.Paste")
			(net "SG")
		)
	)
)
